(kicad_pcb
	(version 20260206)
	(generator "pcbnew")
	(generator_version "10.0")
	(general
		(thickness 1.6)
		(legacy_teardrops no)
	)
	(paper "A4")
	(title_block
		(title "03242023_DA0F0TMBIJ0_F0T_Motherboard_J_brd_V01_OCP.brd")
		(comment 1 "Grand Teton / footprints 2084-2091 of 6105")
	)
	(layers
		(0 "F.Cu" signal "TOP")
		(4 "In1.Cu" signal "GND")
		(6 "In2.Cu" signal "IN1")
		(8 "In3.Cu" signal "GND1")
		(10 "In4.Cu" signal "IN2")
		(12 "In5.Cu" signal "GND2")
		(14 "In6.Cu" signal "IN3")
		(16 "In7.Cu" signal "GND3")
		(18 "In8.Cu" signal "VCC")
		(20 "In9.Cu" signal "VCC1")
		(22 "In10.Cu" signal "GND4")
		(24 "In11.Cu" signal "IN4")
		(26 "In12.Cu" signal "GND5")
		(28 "In13.Cu" signal "IN5")
		(30 "In14.Cu" signal "GND6")
		(32 "In15.Cu" signal "IN6")
		(34 "In16.Cu" signal "GND7")
		(2 "B.Cu" signal "BOTTOM")
		(9 "F.Adhes" user "F.Adhesive")
		(11 "B.Adhes" user "B.Adhesive")
		(13 "F.Paste" user "Package Geometry/Pastemask Top")
		(15 "B.Paste" user "Package Geometry/Pastemask Bottom")
		(5 "F.SilkS" user "Ref Des/Silkscreen Top")
		(7 "B.SilkS" user "Ref Des/Silkscreen Bottom")
		(1 "F.Mask" user "Board Geometry/Soldermask Top")
		(3 "B.Mask" user "Board Geometry/Soldermask Bottom")
		(17 "Dwgs.User" user "User.Drawings")
		(19 "Cmts.User" user "User.Comments")
		(21 "Eco1.User" user "User.Eco1")
		(23 "Eco2.User" user "User.Eco2")
		(25 "Edge.Cuts" user "Board Geometry/Outline")
		(27 "Margin" user)
		(31 "F.CrtYd" user "Package Geometry/Place Bound Top")
		(29 "B.CrtYd" user "Package Geometry/Place Bound Bottom")
		(35 "F.Fab" user "Ref Des/Assembly Top")
		(33 "B.Fab" user "Ref Des/Assembly Bottom")
	)
	(footprint ""
		(layer "F.Cu")
		(at 293.720012 -34.001964 -90)
		(property "Reference" "BT1"
			(at -1.233424 -1.985772 0)
			(unlocked yes)
			(layer "F.SilkS")
			(effects
				(font
					(size 0.7874 0.5842)
					(thickness 0.1524)
				)
				(justify left)
			)
		)
		(property "Value" ""
			(at 0 0 270)
			(layer "F.Fab")
			(effects
				(font
					(size 1.27 1.27)
				)
			)
		)
		(duplicate_pad_numbers_are_jumpers no)
		(fp_line
			(start 3.666236 22.820122)
			(end -3.666236 22.820122)
			(stroke
				(width 0.1524)
				(type default)
			)
			(layer "F.SilkS")
		)
		(fp_line
			(start -4.012692 22.800056)
			(end -3.724148 22.800056)
			(stroke
				(width 0.1524)
				(type default)
			)
			(layer "F.SilkS")
		)
		(fp_line
			(start 3.724148 22.800056)
			(end 4.012692 22.800056)
			(stroke
				(width 0.1524)
				(type default)
			)
			(layer "F.SilkS")
		)
		(fp_line
			(start -3.800094 1.807464)
			(end -3.800094 -1.180084)
			(stroke
				(width 0.1524)
				(type default)
			)
			(layer "F.SilkS")
		)
		(fp_line
			(start 3.899916 1.737614)
			(end 3.899916 -1.260094)
			(stroke
				(width 0.1524)
				(type default)
			)
			(layer "F.SilkS")
		)
		(fp_line
			(start -3.800094 -1.180084)
			(end 3.800094 -1.180084)
			(stroke
				(width 0.1524)
				(type default)
			)
			(layer "F.SilkS")
		)
		(fp_line
			(start 3.800094 -1.180084)
			(end 3.800094 1.807464)
			(stroke
				(width 0.1524)
				(type default)
			)
			(layer "F.SilkS")
		)
		(fp_line
			(start -3.899916 -1.260094)
			(end -3.899916 1.737614)
			(stroke
				(width 0.1524)
				(type default)
			)
			(layer "F.SilkS")
		)
		(fp_line
			(start 3.899916 -1.260094)
			(end -3.899916 -1.260094)
			(stroke
				(width 0.1524)
				(type default)
			)
			(layer "F.SilkS")
		)
		(fp_arc
			(start -3.666236 22.820122)
			(mid -11.149833 12.361061)
			(end -3.800094 1.807464)
			(stroke
				(width 0.1524)
				(type default)
			)
			(layer "F.SilkS")
		)
		(fp_arc
			(start -4.012692 22.800056)
			(mid -11.249872 12.229778)
			(end -3.899916 1.737614)
			(stroke
				(width 0.1524)
				(type default)
			)
			(layer "F.SilkS")
		)
		(fp_arc
			(start 3.800094 1.807464)
			(mid 11.149895 12.361062)
			(end 3.666236 22.820122)
			(stroke
				(width 0.1524)
				(type default)
			)
			(layer "F.SilkS")
		)
		(fp_arc
			(start 3.899916 1.737614)
			(mid 11.249813 12.229779)
			(end 4.012692 22.800056)
			(stroke
				(width 0.1524)
				(type default)
			)
			(layer "F.SilkS")
		)
		(fp_line
			(start 3.666236 22.820122)
			(end -3.666236 22.820122)
			(stroke
				(width 0.1)
				(type default)
			)
			(layer "F.Fab")
		)
		(fp_line
			(start -3.800094 1.807464)
			(end -3.800094 -1.180084)
			(stroke
				(width 0.1)
				(type default)
			)
			(layer "F.Fab")
		)
		(fp_line
			(start -3.800094 -1.180084)
			(end 3.800094 -1.180084)
			(stroke
				(width 0.1)
				(type default)
			)
			(layer "F.Fab")
		)
		(fp_line
			(start 3.800094 -1.180084)
			(end 3.800094 1.807464)
			(stroke
				(width 0.1)
				(type default)
			)
			(layer "F.Fab")
		)
		(fp_arc
			(start -3.666236 22.820122)
			(mid -11.149833 12.361061)
			(end -3.800094 1.807464)
			(stroke
				(width 0.1)
				(type default)
			)
			(layer "F.Fab")
		)
		(fp_arc
			(start 3.800094 1.807464)
			(mid 11.149895 12.361062)
			(end 3.666236 22.820122)
			(stroke
				(width 0.1)
				(type default)
			)
			(layer "F.Fab")
		)
		(fp_text user "-"
			(at 0.26035 22.7076 180)
			(unlocked yes)
			(layer "F.Fab")
			(effects
				(font
					(size 1.905 1.4224)
					(thickness 0.1524)
				)
				(justify left)
			)
		)
		(fp_text user "+"
			(at 0.20955 -2.5908 180)
			(unlocked yes)
			(layer "F.Fab")
			(effects
				(font
					(size 1.905 1.4224)
					(thickness 0.1524)
				)
				(justify left)
			)
		)
		(pad "1" thru_hole rect
			(at 0 0 270)
			(size 1.6256 1.6256)
			(drill 1.1176)
			(layers "*.Cu" "*.Mask")
			(remove_unused_layers no)
			(net "P3V_BAT")
			(clearance 0)
			(padstack
				(mode front_inner_back)
				(layer "Inner"
					(shape circle)
					(size 1.6256 1.6256)
					(clearance 0)
				)
				(layer "B.Cu"
					(shape rect)
					(size 1.6256 1.6256)
					(clearance 0)
				)
			)
		)
		(pad "2" thru_hole circle
			(at 0 19.99996 270)
			(size 1.524 1.524)
			(drill 1.016)
			(layers "*.Cu" "*.Mask")
			(remove_unused_layers no)
			(net "GND")
			(clearance 0)
		)
	)
	(footprint ""
		(layer "F.Cu")
		(at 49.342294 -16.099536 90)
		(property "Reference" "C831"
			(at 0 0 90)
			(layer "F.SilkS")
			(hide yes)
			(effects
				(font
					(size 1.27 1.27)
				)
			)
		)
		(property "Value" ""
			(at 0 0 90)
			(layer "F.Fab")
			(effects
				(font
					(size 1.27 1.27)
				)
			)
		)
		(duplicate_pad_numbers_are_jumpers no)
		(fp_line
			(start 0.299974 -0.150114)
			(end 0.299974 0.150114)
			(stroke
				(width 0.1)
				(type default)
			)
			(layer "F.Fab")
		)
		(fp_line
			(start -0.299974 -0.150114)
			(end 0.299974 -0.150114)
			(stroke
				(width 0.1)
				(type default)
			)
			(layer "F.Fab")
		)
		(fp_line
			(start 0.299974 0.150114)
			(end -0.299974 0.150114)
			(stroke
				(width 0.1)
				(type default)
			)
			(layer "F.Fab")
		)
		(fp_line
			(start -0.299974 0.150114)
			(end -0.299974 -0.150114)
			(stroke
				(width 0.1)
				(type default)
			)
			(layer "F.Fab")
		)
		(pad "1" smd rect
			(at -0.2667 0 90)
			(size 0.3048 0.381)
			(layers "F.Cu" "F.Mask" "F.Paste")
			(net "P5E_CPU1_PE1_TX_C_DP<3>")
		)
		(pad "2" smd rect
			(at 0.2667 0 90)
			(size 0.3048 0.381)
			(layers "F.Cu" "F.Mask" "F.Paste")
			(net "P5E_CPU1_PE1_TX_DP<3>")
		)
	)
	(footprint ""
		(layer "F.Cu")
		(at 70.311518 -402.371052 -90)
		(property "Reference" "C725"
			(at 0 0 270)
			(layer "F.SilkS")
			(hide yes)
			(effects
				(font
					(size 1.27 1.27)
				)
			)
		)
		(property "Value" ""
			(at 0 0 270)
			(layer "F.Fab")
			(effects
				(font
					(size 1.27 1.27)
				)
			)
		)
		(duplicate_pad_numbers_are_jumpers no)
		(fp_line
			(start -0.299974 0.150114)
			(end -0.299974 -0.150114)
			(stroke
				(width 0.1)
				(type default)
			)
			(layer "F.Fab")
		)
		(fp_line
			(start 0.299974 0.150114)
			(end -0.299974 0.150114)
			(stroke
				(width 0.1)
				(type default)
			)
			(layer "F.Fab")
		)
		(fp_line
			(start -0.299974 -0.150114)
			(end 0.299974 -0.150114)
			(stroke
				(width 0.1)
				(type default)
			)
			(layer "F.Fab")
		)
		(fp_line
			(start 0.299974 -0.150114)
			(end 0.299974 0.150114)
			(stroke
				(width 0.1)
				(type default)
			)
			(layer "F.Fab")
		)
		(pad "1" smd rect
			(at -0.2667 0 270)
			(size 0.3048 0.381)
			(layers "F.Cu" "F.Mask" "F.Paste")
			(net "P5E_CPU1_PE0_TX_C_DP<8>")
		)
		(pad "2" smd rect
			(at 0.2667 0 270)
			(size 0.3048 0.381)
			(layers "F.Cu" "F.Mask" "F.Paste")
			(net "P5E_CPU1_PE0_TX_DP<8>")
		)
	)
	(footprint ""
		(layer "F.Cu")
		(at 454.447402 -18.030698)
		(property "Reference" "R3144"
			(at 0 0 0)
			(layer "F.SilkS")
			(hide yes)
			(effects
				(font
					(size 1.27 1.27)
				)
			)
		)
		(property "Value" ""
			(at 0 0 0)
			(layer "F.Fab")
			(effects
				(font
					(size 1.27 1.27)
				)
			)
		)
		(duplicate_pad_numbers_are_jumpers no)
		(fp_line
			(start -0.7874 -0.4064)
			(end 0.7874 -0.4064)
			(stroke
				(width 0.1524)
				(type default)
			)
			(layer "F.SilkS")
		)
		(fp_line
			(start -0.7874 0.4064)
			(end -0.7874 -0.4064)
			(stroke
				(width 0.1524)
				(type default)
			)
			(layer "F.SilkS")
		)
		(fp_line
			(start 0.7874 -0.4064)
			(end 0.7874 0.4064)
			(stroke
				(width 0.1524)
				(type default)
			)
			(layer "F.SilkS")
		)
		(fp_line
			(start 0.7874 0.4064)
			(end -0.7874 0.4064)
			(stroke
				(width 0.1524)
				(type default)
			)
			(layer "F.SilkS")
		)
		(fp_line
			(start -0.67945 -0.305054)
			(end -0.12065 -0.305054)
			(stroke
				(width 0.1)
				(type default)
			)
			(layer "F.Fab")
		)
		(fp_line
			(start -0.67945 0.3048)
			(end -0.67945 -0.305054)
			(stroke
				(width 0.1)
				(type default)
			)
			(layer "F.Fab")
		)
		(fp_line
			(start -0.12065 -0.305054)
			(end -0.12065 -0.2794)
			(stroke
				(width 0.1)
				(type default)
			)
			(layer "F.Fab")
		)
		(fp_line
			(start -0.12065 -0.2794)
			(end 0.12065 -0.2794)
			(stroke
				(width 0.1)
				(type default)
			)
			(layer "F.Fab")
		)
		(fp_line
			(start -0.12065 0.2794)
			(end -0.12065 0.3048)
			(stroke
				(width 0.1)
				(type default)
			)
			(layer "F.Fab")
		)
		(fp_line
			(start -0.12065 0.3048)
			(end -0.67945 0.3048)
			(stroke
				(width 0.1)
				(type default)
			)
			(layer "F.Fab")
		)
		(fp_line
			(start 0.120396 0.2794)
			(end -0.12065 0.2794)
			(stroke
				(width 0.1)
				(type default)
			)
			(layer "F.Fab")
		)
		(fp_line
			(start 0.120396 0.3048)
			(end 0.120396 0.2794)
			(stroke
				(width 0.1)
				(type default)
			)
			(layer "F.Fab")
		)
		(fp_line
			(start 0.12065 -0.3048)
			(end 0.67945 -0.3048)
			(stroke
				(width 0.1)
				(type default)
			)
			(layer "F.Fab")
		)
		(fp_line
			(start 0.12065 -0.2794)
			(end 0.12065 -0.3048)
			(stroke
				(width 0.1)
				(type default)
			)
			(layer "F.Fab")
		)
		(fp_line
			(start 0.67945 -0.3048)
			(end 0.67945 0.3048)
			(stroke
				(width 0.1)
				(type default)
			)
			(layer "F.Fab")
		)
		(fp_line
			(start 0.67945 0.3048)
			(end 0.120396 0.3048)
			(stroke
				(width 0.1)
				(type default)
			)
			(layer "F.Fab")
		)
		(pad "1" smd circle
			(at -0.40005 0)
			(size 0 0)
			(layers "F.Cu" "F.Mask" "F.Paste")
			(net "P12V_OCP_PWRGD_1")
		)
		(pad "2" smd circle
			(at 0.40005 0)
			(size 0 0)
			(layers "F.Cu" "F.Mask" "F.Paste")
			(net "HP_LVC3_OCP_V3_1_P12V_PWRGD")
		)
	)
	(footprint ""
		(layer "F.Cu")
		(at 338.564728 -402.371052 -90)
		(property "Reference" "C1556"
			(at 0 0 270)
			(layer "F.SilkS")
			(hide yes)
			(effects
				(font
					(size 1.27 1.27)
				)
			)
		)
		(property "Value" ""
			(at 0 0 270)
			(layer "F.Fab")
			(effects
				(font
					(size 1.27 1.27)
				)
			)
		)
		(duplicate_pad_numbers_are_jumpers no)
		(fp_line
			(start -0.299974 0.150114)
			(end -0.299974 -0.150114)
			(stroke
				(width 0.1)
				(type default)
			)
			(layer "F.Fab")
		)
		(fp_line
			(start 0.299974 0.150114)
			(end -0.299974 0.150114)
			(stroke
				(width 0.1)
				(type default)
			)
			(layer "F.Fab")
		)
		(fp_line
			(start -0.299974 -0.150114)
			(end 0.299974 -0.150114)
			(stroke
				(width 0.1)
				(type default)
			)
			(layer "F.Fab")
		)
		(fp_line
			(start 0.299974 -0.150114)
			(end 0.299974 0.150114)
			(stroke
				(width 0.1)
				(type default)
			)
			(layer "F.Fab")
		)
		(pad "1" smd rect
			(at -0.2667 0 270)
			(size 0.3048 0.381)
			(layers "F.Cu" "F.Mask" "F.Paste")
			(net "P5E_CPU0_PE4_TX_C_DN<11>")
		)
		(pad "2" smd rect
			(at 0.2667 0 270)
			(size 0.3048 0.381)
			(layers "F.Cu" "F.Mask" "F.Paste")
			(net "P5E_CPU0_PE4_TX_DN<11>")
		)
	)
	(footprint ""
		(layer "F.Cu")
		(at 225.270568 -233.76255)
		(property "Reference" "R978"
			(at 0 0 0)
			(layer "F.SilkS")
			(hide yes)
			(effects
				(font
					(size 1.27 1.27)
				)
			)
		)
		(property "Value" ""
			(at 0 0 0)
			(layer "F.Fab")
			(effects
				(font
					(size 1.27 1.27)
				)
			)
		)
		(duplicate_pad_numbers_are_jumpers no)
		(fp_line
			(start -0.7874 -0.4064)
			(end 0.7874 -0.4064)
			(stroke
				(width 0.1524)
				(type default)
			)
			(layer "F.SilkS")
		)
		(fp_line
			(start -0.7874 0.4064)
			(end -0.7874 -0.4064)
			(stroke
				(width 0.1524)
				(type default)
			)
			(layer "F.SilkS")
		)
		(fp_line
			(start 0.7874 -0.4064)
			(end 0.7874 0.4064)
			(stroke
				(width 0.1524)
				(type default)
			)
			(layer "F.SilkS")
		)
		(fp_line
			(start 0.7874 0.4064)
			(end -0.7874 0.4064)
			(stroke
				(width 0.1524)
				(type default)
			)
			(layer "F.SilkS")
		)
		(fp_line
			(start -0.67945 -0.305054)
			(end -0.12065 -0.305054)
			(stroke
				(width 0.1)
				(type default)
			)
			(layer "F.Fab")
		)
		(fp_line
			(start -0.67945 0.3048)
			(end -0.67945 -0.305054)
			(stroke
				(width 0.1)
				(type default)
			)
			(layer "F.Fab")
		)
		(fp_line
			(start -0.12065 -0.305054)
			(end -0.12065 -0.2794)
			(stroke
				(width 0.1)
				(type default)
			)
			(layer "F.Fab")
		)
		(fp_line
			(start -0.12065 -0.2794)
			(end 0.12065 -0.2794)
			(stroke
				(width 0.1)
				(type default)
			)
			(layer "F.Fab")
		)
		(fp_line
			(start -0.12065 0.2794)
			(end -0.12065 0.3048)
			(stroke
				(width 0.1)
				(type default)
			)
			(layer "F.Fab")
		)
		(fp_line
			(start -0.12065 0.3048)
			(end -0.67945 0.3048)
			(stroke
				(width 0.1)
				(type default)
			)
			(layer "F.Fab")
		)
		(fp_line
			(start 0.120396 0.2794)
			(end -0.12065 0.2794)
			(stroke
				(width 0.1)
				(type default)
			)
			(layer "F.Fab")
		)
		(fp_line
			(start 0.120396 0.3048)
			(end 0.120396 0.2794)
			(stroke
				(width 0.1)
				(type default)
			)
			(layer "F.Fab")
		)
		(fp_line
			(start 0.12065 -0.3048)
			(end 0.67945 -0.3048)
			(stroke
				(width 0.1)
				(type default)
			)
			(layer "F.Fab")
		)
		(fp_line
			(start 0.12065 -0.2794)
			(end 0.12065 -0.3048)
			(stroke
				(width 0.1)
				(type default)
			)
			(layer "F.Fab")
		)
		(fp_line
			(start 0.67945 -0.3048)
			(end 0.67945 0.3048)
			(stroke
				(width 0.1)
				(type default)
			)
			(layer "F.Fab")
		)
		(fp_line
			(start 0.67945 0.3048)
			(end 0.120396 0.3048)
			(stroke
				(width 0.1)
				(type default)
			)
			(layer "F.Fab")
		)
		(pad "1" smd circle
			(at -0.40005 0)
			(size 0 0)
			(layers "F.Cu" "F.Mask" "F.Paste")
			(net "P3V3_AUX")
		)
		(pad "2" smd circle
			(at 0.40005 0)
			(size 0 0)
			(layers "F.Cu" "F.Mask" "F.Paste")
			(net "SMB_S3M_CPU1_3V3AUX_SCL")
		)
	)
	(footprint ""
		(layer "F.Cu")
		(at 94.817438 -402.371052 -90)
		(property "Reference" "C741"
			(at 0 0 270)
			(layer "F.SilkS")
			(hide yes)
			(effects
				(font
					(size 1.27 1.27)
				)
			)
		)
		(property "Value" ""
			(at 0 0 270)
			(layer "F.Fab")
			(effects
				(font
					(size 1.27 1.27)
				)
			)
		)
		(duplicate_pad_numbers_are_jumpers no)
		(fp_line
			(start -0.299974 0.150114)
			(end -0.299974 -0.150114)
			(stroke
				(width 0.1)
				(type default)
			)
			(layer "F.Fab")
		)
		(fp_line
			(start 0.299974 0.150114)
			(end -0.299974 0.150114)
			(stroke
				(width 0.1)
				(type default)
			)
			(layer "F.Fab")
		)
		(fp_line
			(start -0.299974 -0.150114)
			(end 0.299974 -0.150114)
			(stroke
				(width 0.1)
				(type default)
			)
			(layer "F.Fab")
		)
		(fp_line
			(start 0.299974 -0.150114)
			(end 0.299974 0.150114)
			(stroke
				(width 0.1)
				(type default)
			)
			(layer "F.Fab")
		)
		(pad "1" smd rect
			(at -0.2667 0 270)
			(size 0.3048 0.381)
			(layers "F.Cu" "F.Mask" "F.Paste")
			(net "P5E_CPU1_PE0_TX_C_DP<0>")
		)
		(pad "2" smd rect
			(at 0.2667 0 270)
			(size 0.3048 0.381)
			(layers "F.Cu" "F.Mask" "F.Paste")
			(net "P5E_CPU1_PE0_TX_DP<0>")
		)
	)
	(footprint ""
		(layer "F.Cu")
		(at 144.54378 -344.232738 180)
		(property "Reference" "PR639"
			(at 0 0 180)
			(layer "F.SilkS")
			(hide yes)
			(effects
				(font
					(size 1.27 1.27)
				)
			)
		)
		(property "Value" ""
			(at 0 0 180)
			(layer "F.Fab")
			(effects
				(font
					(size 1.27 1.27)
				)
			)
		)
		(duplicate_pad_numbers_are_jumpers no)
		(fp_line
			(start 0.7874 0.4064)
			(end -0.7874 0.4064)
			(stroke
				(width 0.1524)
				(type default)
			)
			(layer "F.SilkS")
		)
		(fp_line
			(start 0.7874 -0.4064)
			(end 0.7874 0.4064)
			(stroke
				(width 0.1524)
				(type default)
			)
			(layer "F.SilkS")
		)
		(fp_line
			(start -0.7874 0.4064)
			(end -0.7874 -0.4064)
			(stroke
				(width 0.1524)
				(type default)
			)
			(layer "F.SilkS")
		)
		(fp_line
			(start -0.7874 -0.4064)
			(end 0.7874 -0.4064)
			(stroke
				(width 0.1524)
				(type default)
			)
			(layer "F.SilkS")
		)
		(fp_line
			(start 0.67945 0.3048)
			(end 0.120396 0.3048)
			(stroke
				(width 0.1)
				(type default)
			)
			(layer "F.Fab")
		)
		(fp_line
			(start 0.67945 -0.3048)
			(end 0.67945 0.3048)
			(stroke
				(width 0.1)
				(type default)
			)
			(layer "F.Fab")
		)
		(fp_line
			(start 0.12065 -0.2794)
			(end 0.12065 -0.3048)
			(stroke
				(width 0.1)
				(type default)
			)
			(layer "F.Fab")
		)
		(fp_line
			(start 0.12065 -0.3048)
			(end 0.67945 -0.3048)
			(stroke
				(width 0.1)
				(type default)
			)
			(layer "F.Fab")
		)
		(fp_line
			(start 0.120396 0.3048)
			(end 0.120396 0.2794)
			(stroke
				(width 0.1)
				(type default)
			)
			(layer "F.Fab")
		)
		(fp_line
			(start 0.120396 0.2794)
			(end -0.12065 0.2794)
			(stroke
				(width 0.1)
				(type default)
			)
			(layer "F.Fab")
		)
		(fp_line
			(start -0.12065 0.3048)
			(end -0.67945 0.3048)
			(stroke
				(width 0.1)
				(type default)
			)
			(layer "F.Fab")
		)
		(fp_line
			(start -0.12065 0.2794)
			(end -0.12065 0.3048)
			(stroke
				(width 0.1)
				(type default)
			)
			(layer "F.Fab")
		)
		(fp_line
			(start -0.12065 -0.2794)
			(end 0.12065 -0.2794)
			(stroke
				(width 0.1)
				(type default)
			)
			(layer "F.Fab")
		)
		(fp_line
			(start -0.12065 -0.305054)
			(end -0.12065 -0.2794)
			(stroke
				(width 0.1)
				(type default)
			)
			(layer "F.Fab")
		)
		(fp_line
			(start -0.67945 0.3048)
			(end -0.67945 -0.305054)
			(stroke
				(width 0.1)
				(type default)
			)
			(layer "F.Fab")
		)
		(fp_line
			(start -0.67945 -0.305054)
			(end -0.12065 -0.305054)
			(stroke
				(width 0.1)
				(type default)
			)
			(layer "F.Fab")
		)
		(pad "1" smd circle
			(at -0.40005 0 180)
			(size 0 0)
			(layers "F.Cu" "F.Mask" "F.Paste")
			(net "P5V")
		)
		(pad "2" smd circle
			(at 0.40005 0 180)
			(size 0 0)
			(layers "F.Cu" "F.Mask" "F.Paste")
			(net "PVCCIN_CPU1_PVCC")
		)
	)
)
